(kicad_pcb
	(version 20241229)
	(generator "pcbnew")
	(generator_version "9.0")
	(general
		(thickness 1.62)
		(legacy_teardrops no)
	)
	(paper "A3")
	(title_block
		(title "COM Express 7 Baseboard")
		(date "2025-02-04")
		(rev "1.1.2")
		(company "Antmicro Ltd")
		(comment 1 "www.antmicro.com")
		(comment 9 "footprints 781-783 of 802")
	)
	(layers
		(0 "F.Cu" signal)
		(4 "In1.Cu" signal)
		(6 "In2.Cu" signal)
		(8 "In3.Cu" signal)
		(10 "In4.Cu" signal)
		(12 "In5.Cu" signal)
		(14 "In6.Cu" signal)
		(2 "B.Cu" signal)
		(9 "F.Adhes" user "F.Adhesive")
		(11 "B.Adhes" user "B.Adhesive")
		(13 "F.Paste" user)
		(15 "B.Paste" user)
		(5 "F.SilkS" user "F.Silkscreen")
		(7 "B.SilkS" user "B.Silkscreen")
		(1 "F.Mask" user)
		(3 "B.Mask" user)
		(17 "Dwgs.User" user "User.Drawings")
		(19 "Cmts.User" user "User.Comments")
		(21 "Eco1.User" user "User.Eco1")
		(23 "Eco2.User" user "User.Eco2")
		(25 "Edge.Cuts" user)
		(27 "Margin" user)
		(31 "F.CrtYd" user "F.Courtyard")
		(29 "B.CrtYd" user "B.Courtyard")
		(35 "F.Fab" user)
		(33 "B.Fab" user)
	)
	(footprint "antmicro-footprints:USON-10_2.5x1mm_P0.5mm"
		(layer "B.Cu")
		(at 100.94 105.365)
		(descr "USON-10 2.5x1mm_ Pitch 0.5mm")
		(tags "USON-10 2.5x1mm Pitch 0.5mm")
		(property "Reference" "U1"
			(at 1.71 0.895 90)
			(layer "B.SilkS")
			(effects
				(font
					(size 0.7 0.7)
					(thickness 0.15)
				)
				(justify right bottom mirror)
			)
		)
		(property "Value" "ESD204DQAR"
			(at 0.018 -2.499 0)
			(layer "B.Fab")
			(effects
				(font
					(size 0.7 0.7)
					(thickness 0.15)
				)
				(justify right bottom mirror)
			)
		)
		(property "Datasheet" "https://www.ti.com/lit/ds/symlink/esd204.pdf?ts=1706004844383&ref_url=https%253A%252F%252Fwww.ti.com%252Finterface%252Fdiodes%252Fesd-protection-diodes%252Fproducts.html"
			(at 0 0 0)
			(layer "F.Fab")
			(hide yes)
			(effects
				(font
					(size 1.27 1.27)
					(thickness 0.15)
				)
			)
		)
		(property "Author" "Antmicro"
			(at 0 0 0)
			(layer "B.Fab")
			(hide yes)
			(effects
				(font
					(size 1 1)
					(thickness 0.15)
				)
				(justify mirror)
			)
		)
		(property "License" "Apache-2.0"
			(at 0 0 0)
			(layer "B.Fab")
			(hide yes)
			(effects
				(font
					(size 1 1)
					(thickness 0.15)
				)
				(justify mirror)
			)
		)
		(property "MPN" "ESD204DQAR"
			(at 0 0 0)
			(layer "B.Fab")
			(hide yes)
			(effects
				(font
					(size 1 1)
					(thickness 0.15)
				)
				(justify mirror)
			)
		)
		(property "Manufacturer" "Texas Instruments"
			(at 0 0 0)
			(layer "B.Fab")
			(hide yes)
			(effects
				(font
					(size 1 1)
					(thickness 0.15)
				)
				(justify mirror)
			)
		)
		(sheetname "2xUSB3.0+RJ45")
		(sheetfile "usb3+rj45.kicad_sch")
		(attr smd)
		(fp_line
			(start -0.5 -1.398)
			(end 0.498 -1.398)
			(stroke
				(width 0.15)
				(type solid)
			)
			(layer "B.SilkS")
		)
		(fp_line
			(start -0.5 1.401)
			(end 0.498 1.401)
			(stroke
				(width 0.15)
				(type solid)
			)
			(layer "B.SilkS")
		)
		(fp_circle
			(center -0.68 1.27)
			(end -0.63 1.27)
			(stroke
				(width 0.15)
				(type solid)
			)
			(fill yes)
			(layer "B.SilkS")
		)
		(fp_rect
			(start -0.8 1.5)
			(end 0.8 -1.499)
			(stroke
				(width 0.05)
				(type solid)
			)
			(fill no)
			(layer "B.CrtYd")
		)
		(fp_line
			(start -0.5 -1.249)
			(end -0.5 1)
			(stroke
				(width 0.15)
				(type solid)
			)
			(layer "B.Fab")
		)
		(fp_line
			(start -0.5 1)
			(end -0.25 1.25)
			(stroke
				(width 0.15)
				(type solid)
			)
			(layer "B.Fab")
		)
		(fp_line
			(start -0.25 1.25)
			(end 0.498 1.25)
			(stroke
				(width 0.15)
				(type solid)
			)
			(layer "B.Fab")
		)
		(fp_line
			(start 0.498 -1.249)
			(end -0.5 -1.249)
			(stroke
				(width 0.15)
				(type solid)
			)
			(layer "B.Fab")
		)
		(fp_line
			(start 0.498 -1.249)
			(end 0.498 1.25)
			(stroke
				(width 0.15)
				(type solid)
			)
			(layer "B.Fab")
		)
		(pad "1" smd roundrect
			(at -0.387 1 90)
			(size 0.25 0.55)
			(layers "B.Cu" "B.Mask" "B.Paste")
			(roundrect_rratio 0.25)
			(net 158 "/2xUSB3.0+RJ45/USBSS_1.RX-")
			(pintype "passive")
			(teardrops
				(best_length_ratio 0.2)
				(max_length 1)
				(best_width_ratio 0.9)
				(max_width 2)
				(curved_edges yes)
				(filter_ratio 0.9)
				(enabled yes)
				(allow_two_segments yes)
				(prefer_zone_connections yes)
			)
		)
		(pad "2" smd roundrect
			(at -0.387 0.5 90)
			(size 0.25 0.55)
			(layers "B.Cu" "B.Mask" "B.Paste")
			(roundrect_rratio 0.25)
			(net 159 "/2xUSB3.0+RJ45/USBSS_1.RX+")
			(pintype "passive")
			(teardrops
				(best_length_ratio 0.2)
				(max_length 1)
				(best_width_ratio 0.9)
				(max_width 2)
				(curved_edges yes)
				(filter_ratio 0.9)
				(enabled yes)
				(allow_two_segments yes)
				(prefer_zone_connections yes)
			)
		)
		(pad "3" smd roundrect
			(at -0.387 0 90)
			(size 0.4 0.55)
			(layers "B.Cu" "B.Mask" "B.Paste")
			(roundrect_rratio 0.25)
			(net 1 "GND")
			(pintype "power_in")
			(teardrops
				(best_length_ratio 0.2)
				(max_length 1)
				(best_width_ratio 0.9)
				(max_width 2)
				(curved_edges yes)
				(filter_ratio 0.9)
				(enabled yes)
				(allow_two_segments yes)
				(prefer_zone_connections yes)
			)
		)
		(pad "4" smd roundrect
			(at -0.387 -0.498 90)
			(size 0.25 0.55)
			(layers "B.Cu" "B.Mask" "B.Paste")
			(roundrect_rratio 0.25)
			(net 47 "/2xUSB3.0+RJ45/USBSS_1.TX-")
			(pintype "passive")
			(teardrops
				(best_length_ratio 0.2)
				(max_length 1)
				(best_width_ratio 0.9)
				(max_width 2)
				(curved_edges yes)
				(filter_ratio 0.9)
				(enabled yes)
				(allow_two_segments yes)
				(prefer_zone_connections yes)
			)
		)
		(pad "5" smd roundrect
			(at -0.387 -0.998 90)
			(size 0.25 0.55)
			(layers "B.Cu" "B.Mask" "B.Paste")
			(roundrect_rratio 0.25)
			(net 44 "/2xUSB3.0+RJ45/USBSS_1.TX+")
			(pintype "passive")
			(teardrops
				(best_length_ratio 0.2)
				(max_length 1)
				(best_width_ratio 0.9)
				(max_width 2)
				(curved_edges yes)
				(filter_ratio 0.9)
				(enabled yes)
				(allow_two_segments yes)
				(prefer_zone_connections yes)
			)
		)
		(pad "6" smd roundrect
			(at 0.385 -0.998 90)
			(size 0.25 0.55)
			(layers "B.Cu" "B.Mask" "B.Paste")
			(roundrect_rratio 0.25)
			(net 44 "/2xUSB3.0+RJ45/USBSS_1.TX+")
			(pintype "passive")
			(teardrops
				(best_length_ratio 0.2)
				(max_length 1)
				(best_width_ratio 0.9)
				(max_width 2)
				(curved_edges yes)
				(filter_ratio 0.9)
				(enabled yes)
				(allow_two_segments yes)
				(prefer_zone_connections yes)
			)
		)
		(pad "7" smd roundrect
			(at 0.385 -0.498 90)
			(size 0.25 0.55)
			(layers "B.Cu" "B.Mask" "B.Paste")
			(roundrect_rratio 0.25)
			(net 47 "/2xUSB3.0+RJ45/USBSS_1.TX-")
			(pintype "passive")
			(teardrops
				(best_length_ratio 0.2)
				(max_length 1)
				(best_width_ratio 0.9)
				(max_width 2)
				(curved_edges yes)
				(filter_ratio 0.9)
				(enabled yes)
				(allow_two_segments yes)
				(prefer_zone_connections yes)
			)
		)
		(pad "8" smd roundrect
			(at 0.385 0 90)
			(size 0.4 0.55)
			(layers "B.Cu" "B.Mask" "B.Paste")
			(roundrect_rratio 0.25)
			(net 1 "GND")
			(pintype "passive")
			(teardrops
				(best_length_ratio 0.2)
				(max_length 1)
				(best_width_ratio 0.9)
				(max_width 2)
				(curved_edges yes)
				(filter_ratio 0.9)
				(enabled yes)
				(allow_two_segments yes)
				(prefer_zone_connections yes)
			)
		)
		(pad "9" smd roundrect
			(at 0.385 0.5 90)
			(size 0.25 0.55)
			(layers "B.Cu" "B.Mask" "B.Paste")
			(roundrect_rratio 0.25)
			(net 159 "/2xUSB3.0+RJ45/USBSS_1.RX+")
			(pintype "passive")
			(teardrops
				(best_length_ratio 0.2)
				(max_length 1)
				(best_width_ratio 0.9)
				(max_width 2)
				(curved_edges yes)
				(filter_ratio 0.9)
				(enabled yes)
				(allow_two_segments yes)
				(prefer_zone_connections yes)
			)
		)
		(pad "10" smd roundrect
			(at 0.385 1 90)
			(size 0.25 0.55)
			(layers "B.Cu" "B.Mask" "B.Paste")
			(roundrect_rratio 0.25)
			(net 158 "/2xUSB3.0+RJ45/USBSS_1.RX-")
			(pintype "passive")
			(teardrops
				(best_length_ratio 0.2)
				(max_length 1)
				(best_width_ratio 0.9)
				(max_width 2)
				(curved_edges yes)
				(filter_ratio 0.9)
				(enabled yes)
				(allow_two_segments yes)
				(prefer_zone_connections yes)
			)
		)
	)
	(footprint "antmicro-footprints:SC70-3"
		(layer "B.Cu")
		(at 104.35 105.365 180)
		(property "Reference" "D25"
			(at -1.05 1.305 0)
			(layer "B.SilkS")
			(effects
				(font
					(size 0.7 0.7)
					(thickness 0.15)
				)
				(justify left bottom mirror)
			)
		)
		(property "Value" "TPD2E2U06_SC70"
			(at 0 -2.3 0)
			(layer "B.Fab")
			(effects
				(font
					(size 0.7 0.7)
					(thickness 0.15)
				)
				(justify left bottom mirror)
			)
		)
		(property "Datasheet" "https://www.ti.com/lit/ds/symlink/tpd2e2u06.pdf?ts=1706006131823&ref_url=https%253A%252F%252Fwww.ti.com%252Finterface%252Fdiodes%252Fesd-protection-diodes%252Fproducts.html"
			(at 0 0 180)
			(layer "F.Fab")
			(hide yes)
			(effects
				(font
					(size 1.27 1.27)
					(thickness 0.15)
				)
			)
		)
		(property "Author" "Antmicro"
			(at 208.7 210.73 0)
			(layer "B.Fab")
			(hide yes)
			(effects
				(font
					(size 1 1)
					(thickness 0.15)
				)
				(justify mirror)
			)
		)
		(property "License" "Apache-2.0"
			(at 208.7 210.73 0)
			(layer "B.Fab")
			(hide yes)
			(effects
				(font
					(size 1 1)
					(thickness 0.15)
				)
				(justify mirror)
			)
		)
		(property "MPN" "TPD2E2U06DCKR"
			(at 208.7 210.73 0)
			(layer "B.Fab")
			(hide yes)
			(effects
				(font
					(size 1 1)
					(thickness 0.15)
				)
				(justify mirror)
			)
		)
		(property "Manufacturer" "Texas Instruments"
			(at 208.7 210.73 0)
			(layer "B.Fab")
			(hide yes)
			(effects
				(font
					(size 1 1)
					(thickness 0.15)
				)
				(justify mirror)
			)
		)
		(sheetname "2xUSB3.0+RJ45")
		(sheetfile "usb3+rj45.kicad_sch")
		(attr smd)
		(fp_line
			(start 0.627 0.999)
			(end 0.627 0.6)
			(stroke
				(width 0.15)
				(type solid)
			)
			(layer "B.SilkS")
		)
		(fp_line
			(start 0.627 0.999)
			(end -0.3 1)
			(stroke
				(width 0.15)
				(type solid)
			)
			(layer "B.SilkS")
		)
		(fp_line
			(start 0.627 -1.001)
			(end 0.627 -0.6)
			(stroke
				(width 0.15)
				(type solid)
			)
			(layer "B.SilkS")
		)
		(fp_line
			(start 0.627 -1.001)
			(end -0.3 -1)
			(stroke
				(width 0.15)
				(type solid)
			)
			(layer "B.SilkS")
		)
		(fp_line
			(start 1.4 0.4)
			(end 0.9 0.4)
			(stroke
				(width 0.05)
				(type solid)
			)
			(layer "B.CrtYd")
		)
		(fp_line
			(start 1.4 -0.4)
			(end 1.4 0.4)
			(stroke
				(width 0.05)
				(type solid)
			)
			(layer "B.CrtYd")
		)
		(fp_line
			(start 0.9 1.3)
			(end -0.9 1.3)
			(stroke
				(width 0.05)
				(type solid)
			)
			(layer "B.CrtYd")
		)
		(fp_line
			(start 0.9 0.4)
			(end 0.9 1.3)
			(stroke
				(width 0.05)
				(type solid)
			)
			(layer "B.CrtYd")
		)
		(fp_line
			(start 0.9 -0.4)
			(end 1.4 -0.4)
			(stroke
				(width 0.05)
				(type solid)
			)
			(layer "B.CrtYd")
		)
		(fp_line
			(start 0.9 -1.3)
			(end 0.9 -0.4)
			(stroke
				(width 0.05)
				(type solid)
			)
			(layer "B.CrtYd")
		)
		(fp_line
			(start -0.9 1)
			(end -0.9 1.3)
			(stroke
				(width 0.05)
				(type solid)
			)
			(layer "B.CrtYd")
		)
		(fp_line
			(start -0.9 -1)
			(end -0.9 -1.3)
			(stroke
				(width 0.05)
				(type solid)
			)
			(layer "B.CrtYd")
		)
		(fp_line
			(start -0.9 -1.3)
			(end 0.9 -1.3)
			(stroke
				(width 0.05)
				(type solid)
			)
			(layer "B.CrtYd")
		)
		(fp_line
			(start -1.4 1)
			(end -0.9 1)
			(stroke
				(width 0.05)
				(type solid)
			)
			(layer "B.CrtYd")
		)
		(fp_line
			(start -1.4 1)
			(end -1.4 -1)
			(stroke
				(width 0.05)
				(type solid)
			)
			(layer "B.CrtYd")
		)
		(fp_line
			(start -1.4 -1)
			(end -0.9 -1)
			(stroke
				(width 0.05)
				(type solid)
			)
			(layer "B.CrtYd")
		)
		(fp_rect
			(start -0.623 0.999)
			(end 0.627 -1.001)
			(stroke
				(width 0.15)
				(type solid)
			)
			(fill no)
			(layer "B.Fab")
		)
		(pad "1" smd rect
			(at -1.051 0.65 90)
			(size 0.6 0.6)
			(layers "B.Cu" "B.Mask" "B.Paste")
			(net 123 "/2xUSB3.0+RJ45/P1_D-")
			(pinfunction "1")
			(pintype "passive")
			(teardrops
				(best_length_ratio 0.2)
				(max_length 1)
				(best_width_ratio 0.9)
				(max_width 2)
				(curved_edges yes)
				(filter_ratio 0.9)
				(enabled yes)
				(allow_two_segments yes)
				(prefer_zone_connections yes)
			)
		)
		(pad "2" smd rect
			(at -1.051 -0.65 90)
			(size 0.6 0.6)
			(layers "B.Cu" "B.Mask" "B.Paste")
			(net 124 "/2xUSB3.0+RJ45/P1_D+")
			(pinfunction "2")
			(pintype "passive")
			(teardrops
				(best_length_ratio 0.2)
				(max_length 1)
				(best_width_ratio 0.9)
				(max_width 2)
				(curved_edges yes)
				(filter_ratio 0.9)
				(enabled yes)
				(allow_two_segments yes)
				(prefer_zone_connections yes)
			)
		)
		(pad "3" smd rect
			(at 1.05 0 90)
			(size 0.6 0.6)
			(layers "B.Cu" "B.Mask" "B.Paste")
			(net 1 "GND")
			(pinfunction "3")
			(pintype "passive")
			(teardrops
				(best_length_ratio 0.2)
				(max_length 1)
				(best_width_ratio 0.9)
				(max_width 2)
				(curved_edges yes)
				(filter_ratio 0.9)
				(enabled yes)
				(allow_two_segments yes)
				(prefer_zone_connections yes)
			)
		)
	)
	(footprint "antmicro-footprints:C_0402_1005Metric"
		(layer "B.Cu")
		(at 124.22 149.26 90)
		(descr "Capacitor SMD 0402")
		(tags "capacitor SMD 0402")
		(property "Reference" "C177"
			(at -1.75 2.33 90)
			(layer "B.SilkS")
			(effects
				(font
					(size 0.7 0.7)
					(thickness 0.15)
				)
				(justify right bottom mirror)
			)
		)
		(property "Value" "C_100n_0402"
			(at -1.022927 -2.155213 90)
			(layer "B.Fab")
			(effects
				(font
					(size 0.7 0.7)
					(thickness 0.15)
				)
				(justify right bottom mirror)
			)
		)
		(property "Datasheet" "https://www.murata.com/products/productdetail?partno=GRM155R61H104KE14%23"
			(at 0 0 90)
			(layer "F.Fab")
			(hide yes)
			(effects
				(font
					(size 1.27 1.27)
					(thickness 0.15)
				)
			)
		)
		(property "Author" "Antmicro"
			(at 273.48 25.04 0)
			(layer "B.Fab")
			(hide yes)
			(effects
				(font
					(size 1 1)
					(thickness 0.15)
				)
				(justify mirror)
			)
		)
		(property "Dielectric" "X5R"
			(at 273.48 25.04 0)
			(layer "B.Fab")
			(hide yes)
			(effects
				(font
					(size 1 1)
					(thickness 0.15)
				)
				(justify mirror)
			)
		)
		(property "License" "Apache-2.0"
			(at 273.48 25.04 0)
			(layer "B.Fab")
			(hide yes)
			(effects
				(font
					(size 1 1)
					(thickness 0.15)
				)
				(justify mirror)
			)
		)
		(property "MPN" "GRM155R61H104KE14D"
			(at 273.48 25.04 0)
			(layer "B.Fab")
			(hide yes)
			(effects
				(font
					(size 1 1)
					(thickness 0.15)
				)
				(justify mirror)
			)
		)
		(property "Manufacturer" "Murata"
			(at 273.48 25.04 0)
			(layer "B.Fab")
			(hide yes)
			(effects
				(font
					(size 1 1)
					(thickness 0.15)
				)
				(justify mirror)
			)
		)
		(property "Public" "False"
			(at 273.48 25.04 0)
			(layer "B.Fab")
			(hide yes)
			(effects
				(font
					(size 1 1)
					(thickness 0.15)
				)
				(justify mirror)
			)
		)
		(property "Val" "100n"
			(at 273.48 25.04 0)
			(layer "B.Fab")
			(hide yes)
			(effects
				(font
					(size 1 1)
					(thickness 0.15)
				)
				(justify mirror)
			)
		)
		(property "Voltage" "50V"
			(at 273.48 25.04 0)
			(layer "B.Fab")
			(hide yes)
			(effects
				(font
					(size 1 1)
					(thickness 0.15)
				)
				(justify mirror)
			)
		)
		(sheetname "KR to SFI #2")
		(sheetfile "kr_sfi.kicad_sch")
		(attr smd)
		(fp_rect
			(start -0.925 0.47)
			(end 0.925 -0.47)
			(stroke
				(width 0.05)
				(type default)
			)
			(fill no)
			(layer "B.CrtYd")
		)
		(fp_line
			(start 0.504 -0.248)
			(end 0.504 0.25)
			(stroke
				(width 0.15)
				(type solid)
			)
			(layer "B.Fab")
		)
		(fp_line
			(start -0.494 -0.248)
			(end 0.504 -0.248)
			(stroke
				(width 0.15)
				(type solid)
			)
			(layer "B.Fab")
		)
		(fp_line
			(start 0.504 0.25)
			(end -0.494 0.25)
			(stroke
				(width 0.15)
				(type solid)
			)
			(layer "B.Fab")
		)
		(fp_line
			(start -0.494 0.25)
			(end -0.494 -0.248)
			(stroke
				(width 0.15)
				(type solid)
			)
			(layer "B.Fab")
		)
		(pad "1" smd roundrect
			(at -0.48 0 90)
			(size 0.59 0.64)
			(layers "B.Cu" "B.Mask" "B.Paste")
			(roundrect_rratio 0.25)
			(net 1 "GND")
			(pintype "passive")
			(teardrops
				(best_length_ratio 0.2)
				(max_length 1)
				(best_width_ratio 0.9)
				(max_width 2)
				(curved_edges yes)
				(filter_ratio 0.9)
				(enabled yes)
				(allow_two_segments yes)
				(prefer_zone_connections yes)
			)
		)
		(pad "2" smd roundrect
			(at 0.48 0 90)
			(size 0.59 0.64)
			(layers "B.Cu" "B.Mask" "B.Paste")
			(roundrect_rratio 0.25)
			(net 78 "+1V8")
			(pintype "passive")
			(teardrops
				(best_length_ratio 0.2)
				(max_length 1)
				(best_width_ratio 0.9)
				(max_width 2)
				(curved_edges yes)
				(filter_ratio 0.9)
				(enabled yes)
				(allow_two_segments yes)
				(prefer_zone_connections yes)
			)
		)
	)
)
